(kicad_pcb
	(version 20260206)
	(generator "pcbnew")
	(generator_version "10.0")
	(general
		(thickness 1.6)
		(legacy_teardrops no)
	)
	(paper "A4")
	(title_block
		(title "Bryce Canyon_IOM_IOC_16318-2_OCP.brd")
		(comment 1 "Bryce Canyon / footprints 97-104 of 1605")
	)
	(layers
		(0 "F.Cu" signal "TOP")
		(4 "In1.Cu" signal "L2GND")
		(6 "In2.Cu" signal "L3")
		(8 "In3.Cu" signal "L4VCC")
		(10 "In4.Cu" signal "L5VCC")
		(12 "In5.Cu" signal "L6")
		(14 "In6.Cu" signal "L7GND")
		(2 "B.Cu" signal "BOTTOM")
		(9 "F.Adhes" user "F.Adhesive")
		(11 "B.Adhes" user "B.Adhesive")
		(13 "F.Paste" user "Package Geometry/Pastemask Top")
		(15 "B.Paste" user "Package Geometry/Pastemask Bottom")
		(5 "F.SilkS" user "Ref Des/Silkscreen Top")
		(7 "B.SilkS" user "Ref Des/Silkscreen Bottom")
		(1 "F.Mask" user "Board Geometry/Soldermask Top")
		(3 "B.Mask" user "Board Geometry/Soldermask Bottom")
		(17 "Dwgs.User" user "User.Drawings")
		(19 "Cmts.User" user "User.Comments")
		(21 "Eco1.User" user "User.Eco1")
		(23 "Eco2.User" user "User.Eco2")
		(25 "Edge.Cuts" user "Board Geometry/Outline")
		(27 "Margin" user)
		(31 "F.CrtYd" user "Package Geometry/Place Bound Top")
		(29 "B.CrtYd" user "Package Geometry/Place Bound Bottom")
		(35 "F.Fab" user "Ref Des/Assembly Top")
		(33 "B.Fab" user "Ref Des/Assembly Bottom")
	)
	(footprint ""
		(layer "F.Cu")
		(at 188.67882 -114.9858 -90)
		(property "Reference" "C744"
			(at 0 0 270)
			(layer "F.SilkS")
			(hide yes)
			(effects
				(font
					(size 1.27 1.27)
				)
			)
		)
		(property "Value" "SC2200P50V2KX-2GP"
			(at 1.1811 -2.7051 270)
			(unlocked yes)
			(layer "F.Fab")
			(hide yes)
			(effects
				(font
					(size 1.016 1.016)
					(thickness 0.1524)
				)
			)
		)
		(property "Device Type" "C402H22"
			(at 1.1811 -4.2291 270)
			(unlocked yes)
			(layer "F.Fab")
			(hide yes)
			(effects
				(font
					(size 1.016 1.016)
					(thickness 0.1524)
				)
			)
		)
		(duplicate_pad_numbers_are_jumpers no)
		(fp_rect
			(start -0.4318 0.9525)
			(end 0.4318 -0.9525)
			(stroke
				(width 0)
				(type default)
			)
			(fill no)
			(layer "F.CrtYd")
		)
		(fp_rect
			(start -0.4318 0.9525)
			(end 0.4318 -0.9525)
			(stroke
				(width 0)
				(type default)
			)
			(fill no)
			(layer "F.Fab")
		)
		(pad "1" smd custom
			(at 0 -0.4445 270)
			(size 0.1524 0.1524)
			(layers "F.Cu" "F.Mask" "F.Paste")
			(net "N62640349")
			(options
				(clearance outline)
				(anchor circle)
			)
			(primitives
				(gr_poly
					(pts
						(arc
							(start 0.3048 -0.2032)
							(mid 0.275042 -0.275042)
							(end 0.2032 -0.3048)
						)
						(arc
							(start -0.2032 -0.3048)
							(mid -0.275042 -0.275042)
							(end -0.3048 -0.2032)
						)
						(arc
							(start -0.3048 0.2032)
							(mid -0.275042 0.275042)
							(end -0.2032 0.3048)
						)
						(arc
							(start 0.2032 0.3048)
							(mid 0.275042 0.275042)
							(end 0.3048 0.2032)
						)
					)
					(width 0)
					(fill yes)
				)
			)
		)
		(pad "2" smd custom
			(at 0 0.4445 270)
			(size 0.1524 0.1524)
			(layers "F.Cu" "F.Mask" "F.Paste")
			(net "GND")
			(options
				(clearance outline)
				(anchor circle)
			)
			(primitives
				(gr_poly
					(pts
						(arc
							(start 0.3048 -0.2032)
							(mid 0.275042 -0.275042)
							(end 0.2032 -0.3048)
						)
						(arc
							(start -0.2032 -0.3048)
							(mid -0.275042 -0.275042)
							(end -0.3048 -0.2032)
						)
						(arc
							(start -0.3048 0.2032)
							(mid -0.275042 0.275042)
							(end -0.2032 0.3048)
						)
						(arc
							(start 0.2032 0.3048)
							(mid 0.275042 0.275042)
							(end 0.3048 0.2032)
						)
					)
					(width 0)
					(fill yes)
				)
			)
		)
	)
	(footprint ""
		(layer "F.Cu")
		(at 194.3608 -83.9724 135)
		(property "Reference" "VIA21"
			(at 0 0 135)
			(layer "F.SilkS")
			(hide yes)
			(effects
				(font
					(size 1.27 1.27)
				)
			)
		)
		(property "Value" "85OHM-8L-1D6MM-L16L18-GP"
			(at 4.064105 0.609655 135)
			(unlocked yes)
			(layer "F.Fab")
			(hide yes)
			(effects
				(font
					(size 1.016 1.016)
					(thickness 0.1524)
				)
			)
		)
		(property "Device Type" "VIA-PCIE-4P-368076"
			(at 4.064105 -0.914474 135)
			(unlocked yes)
			(layer "F.Fab")
			(hide yes)
			(effects
				(font
					(size 1.016 1.016)
					(thickness 0.1524)
				)
			)
		)
		(duplicate_pad_numbers_are_jumpers no)
		(fp_poly
			(pts
				(xy -1.841491 -0.381057) (xy 1.841509 -0.381058) (xy 1.841508 0.380942) (xy -1.841491 0.380942)
			)
			(stroke
				(width 0)
				(type default)
			)
			(fill no)
			(layer "F.CrtYd")
		)
		(fp_poly
			(pts
				(xy -1.841491 -0.381057) (xy 1.841509 -0.381058) (xy 1.841508 0.380942) (xy -1.841491 0.380942)
			)
			(stroke
				(width 0)
				(type default)
			)
			(fill no)
			(layer "F.Fab")
		)
		(pad "1" thru_hole circle
			(at -1.460499 0 135)
			(size 0.508 0.508)
			(drill 0.254)
			(layers "*.Cu" "*.Mask")
			(remove_unused_layers no)
			(net "GND")
			(clearance 0.127)
			(thermal_gap 0.127)
		)
		(pad "2" thru_hole circle
			(at -0.4445 0 135)
			(size 0.508 0.508)
			(drill 0.254)
			(layers "*.Cu" "*.Mask")
			(remove_unused_layers no)
			(net "PCIE_COMP_TO_IOM_13_DP")
			(clearance 0.127)
			(thermal_gap 0.127)
		)
		(pad "3" thru_hole circle
			(at 0.4445 0 135)
			(size 0.508 0.508)
			(drill 0.254)
			(layers "*.Cu" "*.Mask")
			(remove_unused_layers no)
			(net "PCIE_COMP_TO_IOM_13_DN")
			(clearance 0.127)
			(thermal_gap 0.127)
		)
		(pad "4" thru_hole circle
			(at 1.460499 0 135)
			(size 0.508 0.508)
			(drill 0.254)
			(layers "*.Cu" "*.Mask")
			(remove_unused_layers no)
			(net "GND")
			(clearance 0.127)
			(thermal_gap 0.127)
		)
	)
	(footprint ""
		(layer "F.Cu")
		(at 102.999794 -9.99998)
		(property "Reference" ""
			(at 0 0 0)
			(layer "F.SilkS")
			(hide yes)
			(effects
				(font
					(size 1.27 1.27)
				)
			)
		)
		(property "Value" "*"
			(at -6.38175 0.19685 0)
			(unlocked yes)
			(layer "F.Fab")
			(hide yes)
			(effects
				(font
					(size 1.016 1.016)
					(thickness 0.1524)
				)
			)
		)
		(duplicate_pad_numbers_are_jumpers no)
		(fp_poly
			(pts
				(arc
					(start 5.0673 0)
					(mid -5.0673 0)
					(end 5.0673 0)
				)
			)
			(stroke
				(width 0)
				(type default)
			)
			(fill no)
			(layer "B.CrtYd")
		)
		(fp_poly
			(pts
				(arc
					(start 5.0673 0)
					(mid -5.0673 0)
					(end 5.0673 0)
				)
			)
			(stroke
				(width 0)
				(type default)
			)
			(fill no)
			(layer "F.CrtYd")
		)
		(fp_poly
			(pts
				(arc
					(start 5.0673 0)
					(mid -5.0673 0)
					(end 5.0673 0)
				)
			)
			(stroke
				(width 0)
				(type default)
			)
			(fill no)
			(layer "B.Fab")
		)
		(fp_poly
			(pts
				(arc
					(start 5.0673 0)
					(mid -5.0673 0)
					(end 5.0673 0)
				)
			)
			(stroke
				(width 0)
				(type default)
			)
			(fill no)
			(layer "F.Fab")
		)
		(pad "1" thru_hole circle
			(at 0 0)
			(size 9.525 9.525)
			(drill 3.5052)
			(layers "*.Cu" "*.Mask")
			(remove_unused_layers no)
			(net "Net_10")
			(clearance -2.5019)
			(thermal_gap 0.3048)
			(padstack
				(mode front_inner_back)
				(layer "Inner"
					(shape circle)
					(size 3.9116 3.9116)
					(clearance 0.3048)
				)
				(layer "B.Cu"
					(shape circle)
					(size 9.525 9.525)
					(clearance -2.5019)
				)
			)
		)
	)
	(footprint ""
		(layer "F.Cu")
		(at 37.112448 -130.758692 180)
		(property "Reference" "R379"
			(at 0 0 180)
			(layer "F.SilkS")
			(hide yes)
			(effects
				(font
					(size 1.27 1.27)
				)
			)
		)
		(property "Value" "4K7R2F-GP"
			(at 0.064008 -3.993896 180)
			(unlocked yes)
			(layer "F.Fab")
			(hide yes)
			(effects
				(font
					(size 1.016 1.016)
					(thickness 0.1524)
				)
			)
		)
		(property "Device Type" "R402H16"
			(at 0.064008 -5.517896 180)
			(unlocked yes)
			(layer "F.Fab")
			(hide yes)
			(effects
				(font
					(size 1.016 1.016)
					(thickness 0.1524)
				)
			)
		)
		(duplicate_pad_numbers_are_jumpers no)
		(fp_line
			(start 0.508 -0.9398)
			(end -0.508 -0.9398)
			(stroke
				(width 0.1524)
				(type default)
			)
			(layer "F.SilkS")
		)
		(fp_line
			(start -0.508 -0.9398)
			(end -0.508 0.9398)
			(stroke
				(width 0.1524)
				(type default)
			)
			(layer "F.SilkS")
		)
		(fp_rect
			(start -0.508 0.9398)
			(end 0.508 -0.9398)
			(stroke
				(width 0)
				(type default)
			)
			(fill no)
			(layer "F.CrtYd")
		)
		(fp_rect
			(start -0.508 0.9398)
			(end 0.508 -0.9398)
			(stroke
				(width 0)
				(type default)
			)
			(fill no)
			(layer "F.Fab")
		)
		(pad "1" smd custom
			(at 0 -0.4445 180)
			(size 0.1397 0.1397)
			(layers "F.Cu" "F.Mask" "F.Paste")
			(net "P3V3_STBY")
			(options
				(clearance outline)
				(anchor circle)
			)
			(primitives
				(gr_poly
					(pts
						(arc
							(start -0.1778 -0.2794)
							(mid -0.249642 -0.249642)
							(end -0.2794 -0.1778)
						)
						(arc
							(start -0.2794 0.1778)
							(mid -0.249642 0.249642)
							(end -0.1778 0.2794)
						)
						(arc
							(start 0.1778 0.2794)
							(mid 0.249642 0.249642)
							(end 0.2794 0.1778)
						)
						(arc
							(start 0.2794 -0.1778)
							(mid 0.249642 -0.249642)
							(end 0.1778 -0.2794)
						)
					)
					(width 0)
					(fill yes)
				)
			)
		)
		(pad "2" smd custom
			(at 0 0.4445 180)
			(size 0.1397 0.1397)
			(layers "F.Cu" "F.Mask" "F.Paste")
			(net "BMC_GPIOZ7")
			(options
				(clearance outline)
				(anchor circle)
			)
			(primitives
				(gr_poly
					(pts
						(arc
							(start -0.1778 -0.2794)
							(mid -0.249642 -0.249642)
							(end -0.2794 -0.1778)
						)
						(arc
							(start -0.2794 0.1778)
							(mid -0.249642 0.249642)
							(end -0.1778 0.2794)
						)
						(arc
							(start 0.1778 0.2794)
							(mid 0.249642 0.249642)
							(end 0.2794 0.1778)
						)
						(arc
							(start 0.2794 -0.1778)
							(mid 0.249642 -0.249642)
							(end 0.1778 -0.2794)
						)
					)
					(width 0)
					(fill yes)
				)
			)
		)
	)
	(footprint ""
		(layer "F.Cu")
		(at 77.283818 -80.554068 90)
		(property "Reference" "VIA4"
			(at 0 0 90)
			(layer "F.SilkS")
			(hide yes)
			(effects
				(font
					(size 1.27 1.27)
				)
			)
		)
		(property "Value" "85OHM-8L-1D6MM-L16L18-GP"
			(at 4.064 0.6096 90)
			(unlocked yes)
			(layer "F.Fab")
			(hide yes)
			(effects
				(font
					(size 1.016 1.016)
					(thickness 0.1524)
				)
			)
		)
		(property "Device Type" "VIA-PCIE-4P-368076"
			(at 4.064 -0.9144 90)
			(unlocked yes)
			(layer "F.Fab")
			(hide yes)
			(effects
				(font
					(size 1.016 1.016)
					(thickness 0.1524)
				)
			)
		)
		(duplicate_pad_numbers_are_jumpers no)
		(fp_rect
			(start -1.8415 0.381)
			(end 1.8415 -0.381)
			(stroke
				(width 0)
				(type default)
			)
			(fill no)
			(layer "F.CrtYd")
		)
		(fp_rect
			(start -1.8415 0.381)
			(end 1.8415 -0.381)
			(stroke
				(width 0)
				(type default)
			)
			(fill no)
			(layer "F.Fab")
		)
		(pad "1" thru_hole circle
			(at -1.4605 0 90)
			(size 0.508 0.508)
			(drill 0.254)
			(layers "*.Cu" "*.Mask")
			(remove_unused_layers no)
			(net "GND")
			(clearance 0.127)
			(thermal_gap 0.127)
		)
		(pad "2" thru_hole circle
			(at -0.4445 0 90)
			(size 0.508 0.508)
			(drill 0.254)
			(layers "*.Cu" "*.Mask")
			(remove_unused_layers no)
			(net "PCIE_COMP_TO_IOM_19_DP")
			(clearance 0.127)
			(thermal_gap 0.127)
		)
		(pad "3" thru_hole circle
			(at 0.4445 0 90)
			(size 0.508 0.508)
			(drill 0.254)
			(layers "*.Cu" "*.Mask")
			(remove_unused_layers no)
			(net "PCIE_COMP_TO_IOM_19_DN")
			(clearance 0.127)
			(thermal_gap 0.127)
		)
		(pad "4" thru_hole circle
			(at 1.4605 0 90)
			(size 0.508 0.508)
			(drill 0.254)
			(layers "*.Cu" "*.Mask")
			(remove_unused_layers no)
			(net "GND")
			(clearance 0.127)
			(thermal_gap 0.127)
		)
	)
	(footprint ""
		(layer "F.Cu")
		(at 68.6054 -124.5362 -90)
		(property "Reference" "R267"
			(at 0 0 270)
			(layer "F.SilkS")
			(hide yes)
			(effects
				(font
					(size 1.27 1.27)
				)
			)
		)
		(property "Value" "2K2R2J-2-GP"
			(at 0.064008 -3.993896 270)
			(unlocked yes)
			(layer "F.Fab")
			(hide yes)
			(effects
				(font
					(size 1.016 1.016)
					(thickness 0.1524)
				)
			)
		)
		(property "Device Type" "R402H16"
			(at 0.064008 -5.517896 270)
			(unlocked yes)
			(layer "F.Fab")
			(hide yes)
			(effects
				(font
					(size 1.016 1.016)
					(thickness 0.1524)
				)
			)
		)
		(duplicate_pad_numbers_are_jumpers no)
		(fp_line
			(start -0.508 -0.9398)
			(end -0.508 0.9398)
			(stroke
				(width 0.1524)
				(type default)
			)
			(layer "F.SilkS")
		)
		(fp_line
			(start 0.508 -0.9398)
			(end -0.508 -0.9398)
			(stroke
				(width 0.1524)
				(type default)
			)
			(layer "F.SilkS")
		)
		(fp_rect
			(start -0.508 0.9398)
			(end 0.508 -0.9398)
			(stroke
				(width 0)
				(type default)
			)
			(fill no)
			(layer "F.CrtYd")
		)
		(fp_rect
			(start -0.508 0.9398)
			(end 0.508 -0.9398)
			(stroke
				(width 0)
				(type default)
			)
			(fill no)
			(layer "F.Fab")
		)
		(pad "1" smd custom
			(at 0 -0.4445 270)
			(size 0.1397 0.1397)
			(layers "F.Cu" "F.Mask" "F.Paste")
			(net "P3V3_STBY")
			(options
				(clearance outline)
				(anchor circle)
			)
			(primitives
				(gr_poly
					(pts
						(arc
							(start -0.1778 -0.2794)
							(mid -0.249642 -0.249642)
							(end -0.2794 -0.1778)
						)
						(arc
							(start -0.2794 0.1778)
							(mid -0.249642 0.249642)
							(end -0.1778 0.2794)
						)
						(arc
							(start 0.1778 0.2794)
							(mid 0.249642 0.249642)
							(end 0.2794 0.1778)
						)
						(arc
							(start 0.2794 -0.1778)
							(mid 0.249642 -0.249642)
							(end 0.1778 -0.2794)
						)
					)
					(width 0)
					(fill yes)
				)
			)
		)
		(pad "2" smd custom
			(at 0 0.4445 270)
			(size 0.1397 0.1397)
			(layers "F.Cu" "F.Mask" "F.Paste")
			(net "FLA_CS_1_R")
			(options
				(clearance outline)
				(anchor circle)
			)
			(primitives
				(gr_poly
					(pts
						(arc
							(start -0.1778 -0.2794)
							(mid -0.249642 -0.249642)
							(end -0.2794 -0.1778)
						)
						(arc
							(start -0.2794 0.1778)
							(mid -0.249642 0.249642)
							(end -0.1778 0.2794)
						)
						(arc
							(start 0.1778 0.2794)
							(mid 0.249642 0.249642)
							(end 0.2794 0.1778)
						)
						(arc
							(start 0.2794 -0.1778)
							(mid 0.249642 -0.249642)
							(end 0.1778 -0.2794)
						)
					)
					(width 0)
					(fill yes)
				)
			)
		)
	)
	(footprint ""
		(layer "F.Cu")
		(at 74.934572 -167.279828 180)
		(property "Reference" "C241"
			(at 0 0 180)
			(layer "F.SilkS")
			(hide yes)
			(effects
				(font
					(size 1.27 1.27)
				)
			)
		)
		(property "Value" "SC1U16V3KX-5GP"
			(at 0 -2.8194 180)
			(unlocked yes)
			(layer "F.Fab")
			(hide yes)
			(effects
				(font
					(size 1.016 1.016)
					(thickness 0.1524)
				)
			)
		)
		(property "Device Type" "C603H36"
			(at 0 -4.3434 180)
			(unlocked yes)
			(layer "F.Fab")
			(hide yes)
			(effects
				(font
					(size 1.016 1.016)
					(thickness 0.1524)
				)
			)
		)
		(duplicate_pad_numbers_are_jumpers no)
		(fp_line
			(start 0.508 0)
			(end -0.508 0)
			(stroke
				(width 0.2032)
				(type default)
			)
			(layer "F.SilkS")
		)
		(fp_rect
			(start -0.5842 1.3335)
			(end 0.5842 -1.3335)
			(stroke
				(width 0)
				(type default)
			)
			(fill no)
			(layer "F.CrtYd")
		)
		(fp_rect
			(start -0.5842 1.3335)
			(end 0.5842 -1.3335)
			(stroke
				(width 0)
				(type default)
			)
			(fill no)
			(layer "F.Fab")
		)
		(pad "1" smd custom
			(at 0 -0.762 180)
			(size 0.2159 0.2159)
			(layers "F.Cu" "F.Mask" "F.Paste")
			(net "TPS74801_P1V15_STBY_BIAS")
			(options
				(clearance outline)
				(anchor circle)
			)
			(primitives
				(gr_poly
					(pts
						(arc
							(start -0.3302 -0.4318)
							(mid -0.402042 -0.402042)
							(end -0.4318 -0.3302)
						)
						(arc
							(start -0.4318 0.3302)
							(mid -0.402042 0.402042)
							(end -0.3302 0.4318)
						)
						(arc
							(start 0.3302 0.4318)
							(mid 0.402042 0.402042)
							(end 0.4318 0.3302)
						)
						(arc
							(start 0.4318 -0.3302)
							(mid 0.402042 -0.402042)
							(end 0.3302 -0.4318)
						)
					)
					(width 0)
					(fill yes)
				)
			)
		)
		(pad "2" smd custom
			(at 0 0.762 180)
			(size 0.2159 0.2159)
			(layers "F.Cu" "F.Mask" "F.Paste")
			(net "GND")
			(options
				(clearance outline)
				(anchor circle)
			)
			(primitives
				(gr_poly
					(pts
						(arc
							(start -0.3302 -0.4318)
							(mid -0.402042 -0.402042)
							(end -0.4318 -0.3302)
						)
						(arc
							(start -0.4318 0.3302)
							(mid -0.402042 0.402042)
							(end -0.3302 0.4318)
						)
						(arc
							(start 0.3302 0.4318)
							(mid 0.402042 0.402042)
							(end 0.4318 0.3302)
						)
						(arc
							(start 0.4318 -0.3302)
							(mid 0.402042 -0.402042)
							(end 0.3302 -0.4318)
						)
					)
					(width 0)
					(fill yes)
				)
			)
		)
	)
	(footprint ""
		(layer "F.Cu")
		(at 63.440564 -144.045432 90)
		(property "Reference" "R181"
			(at 0 0 90)
			(layer "F.SilkS")
			(hide yes)
			(effects
				(font
					(size 1.27 1.27)
				)
			)
		)
		(property "Value" "2K2R2F-GP"
			(at 0.064008 -3.993896 90)
			(unlocked yes)
			(layer "F.Fab")
			(hide yes)
			(effects
				(font
					(size 1.016 1.016)
					(thickness 0.1524)
				)
			)
		)
		(property "Device Type" "R402H16"
			(at 0.064008 -5.517896 90)
			(unlocked yes)
			(layer "F.Fab")
			(hide yes)
			(effects
				(font
					(size 1.016 1.016)
					(thickness 0.1524)
				)
			)
		)
		(duplicate_pad_numbers_are_jumpers no)
		(fp_line
			(start 0.508 -0.9398)
			(end -0.508 -0.9398)
			(stroke
				(width 0.1524)
				(type default)
			)
			(layer "F.SilkS")
		)
		(fp_line
			(start -0.508 -0.9398)
			(end -0.508 0.9398)
			(stroke
				(width 0.1524)
				(type default)
			)
			(layer "F.SilkS")
		)
		(fp_rect
			(start -0.508 0.9398)
			(end 0.508 -0.9398)
			(stroke
				(width 0)
				(type default)
			)
			(fill no)
			(layer "F.CrtYd")
		)
		(fp_rect
			(start -0.508 0.9398)
			(end 0.508 -0.9398)
			(stroke
				(width 0)
				(type default)
			)
			(fill no)
			(layer "F.Fab")
		)
		(pad "1" smd custom
			(at 0 -0.4445 90)
			(size 0.1397 0.1397)
			(layers "F.Cu" "F.Mask" "F.Paste")
			(net "I2C_SCC_SCL_OUT")
			(options
				(clearance outline)
				(anchor circle)
			)
			(primitives
				(gr_poly
					(pts
						(arc
							(start -0.1778 -0.2794)
							(mid -0.249642 -0.249642)
							(end -0.2794 -0.1778)
						)
						(arc
							(start -0.2794 0.1778)
							(mid -0.249642 0.249642)
							(end -0.1778 0.2794)
						)
						(arc
							(start 0.1778 0.2794)
							(mid 0.249642 0.249642)
							(end 0.2794 0.1778)
						)
						(arc
							(start 0.2794 -0.1778)
							(mid 0.249642 -0.249642)
							(end 0.1778 -0.2794)
						)
					)
					(width 0)
					(fill yes)
				)
			)
		)
		(pad "2" smd custom
			(at 0 0.4445 90)
			(size 0.1397 0.1397)
			(layers "F.Cu" "F.Mask" "F.Paste")
			(net "P3V3_STBY")
			(options
				(clearance outline)
				(anchor circle)
			)
			(primitives
				(gr_poly
					(pts
						(arc
							(start -0.1778 -0.2794)
							(mid -0.249642 -0.249642)
							(end -0.2794 -0.1778)
						)
						(arc
							(start -0.2794 0.1778)
							(mid -0.249642 0.249642)
							(end -0.1778 0.2794)
						)
						(arc
							(start 0.1778 0.2794)
							(mid 0.249642 0.249642)
							(end 0.2794 0.1778)
						)
						(arc
							(start 0.2794 -0.1778)
							(mid 0.249642 -0.249642)
							(end 0.1778 -0.2794)
						)
					)
					(width 0)
					(fill yes)
				)
			)
		)
	)
)
